(kicad_pcb
	(version 20260206)
	(generator "pcbnew")
	(generator_version "10.0")
	(general
		(thickness 1.6)
		(legacy_teardrops no)
	)
	(paper "A4")
	(title_block
		(title "peb — Lightning_PEB_BRD.brd")
		(comment 1 "Lightning (Wiwynn / Facebook NVMe JBOF) / footprint 432 of 2563 (GF9), pads 1-113 of 200")
	)
	(layers
		(0 "F.Cu" signal "TOP")
		(4 "In1.Cu" signal "L2GND")
		(6 "In2.Cu" signal "L3")
		(8 "In3.Cu" signal "L4VCC")
		(10 "In4.Cu" signal "L5VCC")
		(12 "In5.Cu" signal "L6")
		(14 "In6.Cu" signal "L7GND")
		(2 "B.Cu" signal "BOTTOM")
		(9 "F.Adhes" user "F.Adhesive")
		(11 "B.Adhes" user "B.Adhesive")
		(13 "F.Paste" user "Package Geometry/Pastemask Top")
		(15 "B.Paste" user "Package Geometry/Pastemask Bottom")
		(5 "F.SilkS" user "Ref Des/Silkscreen Top")
		(7 "B.SilkS" user "Ref Des/Silkscreen Bottom")
		(1 "F.Mask" user "Board Geometry/Soldermask Top")
		(3 "B.Mask" user "Board Geometry/Soldermask Bottom")
		(17 "Dwgs.User" user "User.Drawings")
		(19 "Cmts.User" user "User.Comments")
		(21 "Eco1.User" user "User.Eco1")
		(23 "Eco2.User" user "User.Eco2")
		(25 "Edge.Cuts" user "Board Geometry/Outline")
		(27 "Margin" user)
		(31 "F.CrtYd" user "Package Geometry/Place Bound Top")
		(29 "B.CrtYd" user "Package Geometry/Place Bound Bottom")
		(35 "F.Fab" user "Ref Des/Assembly Top")
		(33 "B.Fab" user "Ref Des/Assembly Bottom")
	)
	(footprint ""
		(layer "F.Cu")
		(at 181.30012 -226.70008 180)
		(property "Reference" "GF9"
			(at 0 0 180)
			(layer "F.SilkS")
			(hide yes)
			(effects
				(font
					(size 1.27 1.27)
				)
			)
		)
		(property "Value" "GF-200P-8-GP-U1"
			(at -43.1673 -7.6327 180)
			(unlocked yes)
			(layer "F.Fab")
			(hide yes)
			(effects
				(font
					(size 1.016 1.016)
					(thickness 0.1524)
				)
			)
		)
		(property "Device Type" "GF-200P-8-U1"
			(at -43.1673 -9.1567 180)
			(unlocked yes)
			(layer "F.Fab")
			(hide yes)
			(effects
				(font
					(size 1.016 1.016)
					(thickness 0.1524)
				)
			)
		)
		(duplicate_pad_numbers_are_jumpers no)
		(pad "A1" smd rect
			(at -36.399978 -1.1557 180)
			(size 0.5588 2.3114)
			(layers "F.Cu" "F.Mask" "F.Paste")
			(net "GND")
		)
		(pad "A2" smd rect
			(at -35.599878 -1.1557 180)
			(size 0.5588 2.3114)
			(layers "F.Cu" "F.Mask" "F.Paste")
			(net "PCIE_TX_N38")
		)
		(pad "A3" smd rect
			(at -34.800032 -1.1557 180)
			(size 0.5588 2.3114)
			(layers "F.Cu" "F.Mask" "F.Paste")
			(net "PCIE_TX_P38")
		)
		(pad "A4" smd rect
			(at -33.999932 -1.1557 180)
			(size 0.5588 2.3114)
			(layers "F.Cu" "F.Mask" "F.Paste")
			(net "GND")
		)
		(pad "A5" smd rect
			(at -33.200086 -1.1557 180)
			(size 0.5588 2.3114)
			(layers "F.Cu" "F.Mask" "F.Paste")
			(net "GND")
		)
		(pad "A6" smd rect
			(at -32.399986 -1.1557 180)
			(size 0.5588 2.3114)
			(layers "F.Cu" "F.Mask" "F.Paste")
			(net "PCIE_TX_N39")
		)
		(pad "A7" smd rect
			(at -31.599886 -1.1557 180)
			(size 0.5588 2.3114)
			(layers "F.Cu" "F.Mask" "F.Paste")
			(net "PCIE_TX_P39")
		)
		(pad "A8" smd rect
			(at -30.80004 -1.1557 180)
			(size 0.5588 2.3114)
			(layers "F.Cu" "F.Mask" "F.Paste")
			(net "GND")
		)
		(pad "A9" smd rect
			(at -29.99994 -1.1557 180)
			(size 0.5588 2.3114)
			(layers "F.Cu" "F.Mask" "F.Paste")
			(net "SSD_PERST#3_R")
		)
		(pad "A10" smd rect
			(at -29.200094 -1.1557 180)
			(size 0.5588 2.3114)
			(layers "F.Cu" "F.Mask" "F.Paste")
			(net "SSD_PWREN3_R")
		)
		(pad "A11" smd rect
			(at -28.399994 -1.1557 180)
			(size 0.5588 2.3114)
			(layers "F.Cu" "F.Mask" "F.Paste")
			(net "SSD_ATNLED#3_R")
		)
		(pad "A12" smd rect
			(at -27.599894 -1.1557 180)
			(size 0.5588 2.3114)
			(layers "F.Cu" "F.Mask" "F.Paste")
			(net "SSD_PRSNT#3_R")
		)
		(pad "A13" smd rect
			(at -26.800048 -1.1557 180)
			(size 0.5588 2.3114)
			(layers "F.Cu" "F.Mask" "F.Paste")
			(net "GND")
		)
		(pad "A14" smd rect
			(at -25.999948 -1.1557 180)
			(size 0.5588 2.3114)
			(layers "F.Cu" "F.Mask" "F.Paste")
			(net "PCIE_TX_N40")
		)
		(pad "A15" smd rect
			(at -25.200102 -1.1557 180)
			(size 0.5588 2.3114)
			(layers "F.Cu" "F.Mask" "F.Paste")
			(net "PCIE_TX_P40")
		)
		(pad "A16" smd rect
			(at -24.400002 -1.1557 180)
			(size 0.5588 2.3114)
			(layers "F.Cu" "F.Mask" "F.Paste")
			(net "GND")
		)
		(pad "A17" smd rect
			(at -23.599902 -1.1557 180)
			(size 0.5588 2.3114)
			(layers "F.Cu" "F.Mask" "F.Paste")
			(net "GND")
		)
		(pad "A18" smd rect
			(at -22.800056 -1.1557 180)
			(size 0.5588 2.3114)
			(layers "F.Cu" "F.Mask" "F.Paste")
			(net "PCIE_TX_N41")
		)
		(pad "A19" smd rect
			(at -21.999956 -1.1557 180)
			(size 0.5588 2.3114)
			(layers "F.Cu" "F.Mask" "F.Paste")
			(net "PCIE_TX_P41")
		)
		(pad "A20" smd rect
			(at -21.20011 -1.1557 180)
			(size 0.5588 2.3114)
			(layers "F.Cu" "F.Mask" "F.Paste")
			(net "GND")
		)
		(pad "A21" smd rect
			(at -20.40001 -1.1557 180)
			(size 0.5588 2.3114)
			(layers "F.Cu" "F.Mask" "F.Paste")
			(net "GND")
		)
		(pad "A22" smd rect
			(at -19.59991 -1.1557 180)
			(size 0.5588 2.3114)
			(layers "F.Cu" "F.Mask" "F.Paste")
			(net "PCIE_TX_N42")
		)
		(pad "A23" smd rect
			(at -18.800064 -1.1557 180)
			(size 0.5588 2.3114)
			(layers "F.Cu" "F.Mask" "F.Paste")
			(net "PCIE_TX_P42")
		)
		(pad "A24" smd rect
			(at -17.999964 -1.1557 180)
			(size 0.5588 2.3114)
			(layers "F.Cu" "F.Mask" "F.Paste")
			(net "GND")
		)
		(pad "A25" smd rect
			(at -17.200118 -1.1557 180)
			(size 0.5588 2.3114)
			(layers "F.Cu" "F.Mask" "F.Paste")
			(net "GND")
		)
		(pad "A26" smd rect
			(at -16.400018 -1.1557 180)
			(size 0.5588 2.3114)
			(layers "F.Cu" "F.Mask" "F.Paste")
			(net "PCIE_TX_N43")
		)
		(pad "A27" smd rect
			(at -15.599918 -1.1557 180)
			(size 0.5588 2.3114)
			(layers "F.Cu" "F.Mask" "F.Paste")
			(net "PCIE_TX_P43")
		)
		(pad "A28" smd rect
			(at -14.800072 -1.1557 180)
			(size 0.5588 2.3114)
			(layers "F.Cu" "F.Mask" "F.Paste")
			(net "GND")
		)
		(pad "A29" smd rect
			(at -13.999972 -1.1557 180)
			(size 0.5588 2.3114)
			(layers "F.Cu" "F.Mask" "F.Paste")
			(net "GND")
		)
		(pad "A30" smd rect
			(at -13.200126 -1.1557 180)
			(size 0.5588 2.3114)
			(layers "F.Cu" "F.Mask" "F.Paste")
			(net "PCIE_TX_N44")
		)
		(pad "A31" smd rect
			(at -12.400026 -1.1557 180)
			(size 0.5588 2.3114)
			(layers "F.Cu" "F.Mask" "F.Paste")
			(net "PCIE_TX_P44")
		)
		(pad "A32" smd rect
			(at -11.599926 -1.1557 180)
			(size 0.5588 2.3114)
			(layers "F.Cu" "F.Mask" "F.Paste")
			(net "GND")
		)
		(pad "A33" smd rect
			(at -10.80008 -1.1557 180)
			(size 0.5588 2.3114)
			(layers "F.Cu" "F.Mask" "F.Paste")
			(net "GND")
		)
		(pad "A34" smd rect
			(at -9.99998 -1.1557 180)
			(size 0.5588 2.3114)
			(layers "F.Cu" "F.Mask" "F.Paste")
			(net "PCIE_TX_N45")
		)
		(pad "A35" smd rect
			(at -9.19988 -1.1557 180)
			(size 0.5588 2.3114)
			(layers "F.Cu" "F.Mask" "F.Paste")
			(net "PCIE_TX_P45")
		)
		(pad "A36" smd rect
			(at -8.400034 -1.1557 180)
			(size 0.5588 2.3114)
			(layers "F.Cu" "F.Mask" "F.Paste")
			(net "GND")
		)
		(pad "A37" smd rect
			(at -7.599934 -1.1557 180)
			(size 0.5588 2.3114)
			(layers "F.Cu" "F.Mask" "F.Paste")
			(net "GND")
		)
		(pad "A38" smd rect
			(at -6.800088 -1.1557 180)
			(size 0.5588 2.3114)
			(layers "F.Cu" "F.Mask" "F.Paste")
			(net "PCIE_TX_N46")
		)
		(pad "A39" smd rect
			(at -5.999988 -1.1557 180)
			(size 0.5588 2.3114)
			(layers "F.Cu" "F.Mask" "F.Paste")
			(net "PCIE_TX_P46")
		)
		(pad "A40" smd rect
			(at -5.199888 -1.1557 180)
			(size 0.5588 2.3114)
			(layers "F.Cu" "F.Mask" "F.Paste")
			(net "GND")
		)
		(pad "A41" smd rect
			(at -4.400042 -1.1557 180)
			(size 0.5588 2.3114)
			(layers "F.Cu" "F.Mask" "F.Paste")
			(net "GND")
		)
		(pad "A42" smd rect
			(at -3.599942 -1.1557 180)
			(size 0.5588 2.3114)
			(layers "F.Cu" "F.Mask" "F.Paste")
			(net "PCIE_TX_N47")
		)
		(pad "A43" smd rect
			(at -2.800096 -1.1557 180)
			(size 0.5588 2.3114)
			(layers "F.Cu" "F.Mask" "F.Paste")
			(net "PCIE_TX_P47")
		)
		(pad "A44" smd rect
			(at -1.999996 -1.1557 180)
			(size 0.5588 2.3114)
			(layers "F.Cu" "F.Mask" "F.Paste")
			(net "GND")
		)
		(pad "A45" smd rect
			(at 1.999996 -1.1557 180)
			(size 0.5588 2.3114)
			(layers "F.Cu" "F.Mask" "F.Paste")
			(net "SSD_ATNLED#7_R")
		)
		(pad "A46" smd rect
			(at 2.800096 -1.1557 180)
			(size 0.5588 1.8796)
			(drill
				(offset 0 -0.2159)
			)
			(layers "F.Cu" "F.Mask" "F.Paste")
			(net "SSD_PRSNT#7_R")
		)
		(pad "A47" smd rect
			(at 3.599942 -1.1557 180)
			(size 0.5588 2.3114)
			(layers "F.Cu" "F.Mask" "F.Paste")
			(net "GND")
		)
		(pad "A48" smd rect
			(at 4.400042 -1.1557 180)
			(size 0.5588 2.3114)
			(layers "F.Cu" "F.Mask" "F.Paste")
			(net "PCIE_TX_N48")
		)
		(pad "A49" smd rect
			(at 5.199888 -1.1557 180)
			(size 0.5588 2.3114)
			(layers "F.Cu" "F.Mask" "F.Paste")
			(net "PCIE_TX_P48")
		)
		(pad "A50" smd rect
			(at 5.999988 -1.1557 180)
			(size 0.5588 2.3114)
			(layers "F.Cu" "F.Mask" "F.Paste")
			(net "GND")
		)
		(pad "A51" smd rect
			(at 6.800088 -1.1557 180)
			(size 0.5588 2.3114)
			(layers "F.Cu" "F.Mask" "F.Paste")
			(net "GND")
		)
		(pad "A52" smd rect
			(at 7.599934 -1.1557 180)
			(size 0.5588 2.3114)
			(layers "F.Cu" "F.Mask" "F.Paste")
			(net "PCIE_TX_N49")
		)
		(pad "A53" smd rect
			(at 8.400034 -1.1557 180)
			(size 0.5588 2.3114)
			(layers "F.Cu" "F.Mask" "F.Paste")
			(net "PCIE_TX_P49")
		)
		(pad "A54" smd rect
			(at 9.19988 -1.1557 180)
			(size 0.5588 2.3114)
			(layers "F.Cu" "F.Mask" "F.Paste")
			(net "GND")
		)
		(pad "A55" smd rect
			(at 9.99998 -1.1557 180)
			(size 0.5588 2.3114)
			(layers "F.Cu" "F.Mask" "F.Paste")
			(net "GND")
		)
		(pad "A56" smd rect
			(at 10.80008 -1.1557 180)
			(size 0.5588 2.3114)
			(layers "F.Cu" "F.Mask" "F.Paste")
			(net "PCIE_TX_N50")
		)
		(pad "A57" smd rect
			(at 11.599926 -1.1557 180)
			(size 0.5588 2.3114)
			(layers "F.Cu" "F.Mask" "F.Paste")
			(net "PCIE_TX_P50")
		)
		(pad "A58" smd rect
			(at 12.400026 -1.1557 180)
			(size 0.5588 2.3114)
			(layers "F.Cu" "F.Mask" "F.Paste")
			(net "GND")
		)
		(pad "A59" smd rect
			(at 13.200126 -1.1557 180)
			(size 0.5588 2.3114)
			(layers "F.Cu" "F.Mask" "F.Paste")
			(net "GND")
		)
		(pad "A60" smd rect
			(at 13.999972 -1.1557 180)
			(size 0.5588 2.3114)
			(layers "F.Cu" "F.Mask" "F.Paste")
			(net "PCIE_TX_N51")
		)
		(pad "A61" smd rect
			(at 14.800072 -1.1557 180)
			(size 0.5588 2.3114)
			(layers "F.Cu" "F.Mask" "F.Paste")
			(net "PCIE_TX_P51")
		)
		(pad "A62" smd rect
			(at 15.599918 -1.1557 180)
			(size 0.5588 2.3114)
			(layers "F.Cu" "F.Mask" "F.Paste")
			(net "GND")
		)
		(pad "A63" smd rect
			(at 16.400018 -1.1557 180)
			(size 0.5588 2.3114)
			(layers "F.Cu" "F.Mask" "F.Paste")
			(net "SSD_PWREN2_R")
		)
		(pad "A64" smd rect
			(at 17.200118 -1.1557 180)
			(size 0.5588 2.3114)
			(layers "F.Cu" "F.Mask" "F.Paste")
			(net "SSD_ATNLED#2_R")
		)
		(pad "A65" smd rect
			(at 17.999964 -1.1557 180)
			(size 0.5588 2.3114)
			(layers "F.Cu" "F.Mask" "F.Paste")
			(net "SSD_PRSNT#2_R")
		)
		(pad "A66" smd rect
			(at 18.800064 -1.1557 180)
			(size 0.5588 2.3114)
			(layers "F.Cu" "F.Mask" "F.Paste")
			(net "GND")
		)
		(pad "A67" smd rect
			(at 19.59991 -1.1557 180)
			(size 0.5588 2.3114)
			(layers "F.Cu" "F.Mask" "F.Paste")
			(net "PCIE_TX_N52")
		)
		(pad "A68" smd rect
			(at 20.40001 -1.1557 180)
			(size 0.5588 2.3114)
			(layers "F.Cu" "F.Mask" "F.Paste")
			(net "PCIE_TX_P52")
		)
		(pad "A69" smd rect
			(at 21.20011 -1.1557 180)
			(size 0.5588 2.3114)
			(layers "F.Cu" "F.Mask" "F.Paste")
			(net "GND")
		)
		(pad "A70" smd rect
			(at 21.999956 -1.1557 180)
			(size 0.5588 2.3114)
			(layers "F.Cu" "F.Mask" "F.Paste")
			(net "GND")
		)
		(pad "A71" smd rect
			(at 22.800056 -1.1557 180)
			(size 0.5588 2.3114)
			(layers "F.Cu" "F.Mask" "F.Paste")
			(net "PCIE_TX_N53")
		)
		(pad "A72" smd rect
			(at 23.599902 -1.1557 180)
			(size 0.5588 2.3114)
			(layers "F.Cu" "F.Mask" "F.Paste")
			(net "PCIE_TX_P53")
		)
		(pad "A73" smd rect
			(at 24.400002 -1.1557 180)
			(size 0.5588 2.3114)
			(layers "F.Cu" "F.Mask" "F.Paste")
			(net "GND")
		)
		(pad "A74" smd rect
			(at 25.200102 -1.1557 180)
			(size 0.5588 2.3114)
			(layers "F.Cu" "F.Mask" "F.Paste")
			(net "GND")
		)
		(pad "A75" smd rect
			(at 25.999948 -1.1557 180)
			(size 0.5588 2.3114)
			(layers "F.Cu" "F.Mask" "F.Paste")
			(net "PCIE_TX_N54")
		)
		(pad "A76" smd rect
			(at 26.800048 -1.1557 180)
			(size 0.5588 2.3114)
			(layers "F.Cu" "F.Mask" "F.Paste")
			(net "PCIE_TX_P54")
		)
		(pad "A77" smd rect
			(at 27.599894 -1.1557 180)
			(size 0.5588 2.3114)
			(layers "F.Cu" "F.Mask" "F.Paste")
			(net "GND")
		)
		(pad "A78" smd rect
			(at 28.399994 -1.1557 180)
			(size 0.5588 2.3114)
			(layers "F.Cu" "F.Mask" "F.Paste")
			(net "GND")
		)
		(pad "A79" smd rect
			(at 29.200094 -1.1557 180)
			(size 0.5588 2.3114)
			(layers "F.Cu" "F.Mask" "F.Paste")
			(net "PCIE_TX_N55")
		)
		(pad "A80" smd rect
			(at 29.99994 -1.1557 180)
			(size 0.5588 2.3114)
			(layers "F.Cu" "F.Mask" "F.Paste")
			(net "PCIE_TX_P55")
		)
		(pad "A81" smd rect
			(at 30.80004 -1.1557 180)
			(size 0.5588 2.3114)
			(layers "F.Cu" "F.Mask" "F.Paste")
			(net "GND")
		)
		(pad "A82" smd rect
			(at 31.599886 -1.1557 180)
			(size 0.5588 2.3114)
			(layers "F.Cu" "F.Mask" "F.Paste")
			(net "GND")
		)
		(pad "A83" smd rect
			(at 32.399986 -1.1557 180)
			(size 0.5588 2.3114)
			(layers "F.Cu" "F.Mask" "F.Paste")
			(net "PCIE_TX_N56")
		)
		(pad "A84" smd rect
			(at 33.200086 -1.1557 180)
			(size 0.5588 2.3114)
			(layers "F.Cu" "F.Mask" "F.Paste")
			(net "PCIE_TX_P56")
		)
		(pad "A85" smd rect
			(at 33.999932 -1.1557 180)
			(size 0.5588 2.3114)
			(layers "F.Cu" "F.Mask" "F.Paste")
			(net "GND")
		)
		(pad "A86" smd rect
			(at 34.800032 -1.1557 180)
			(size 0.5588 2.3114)
			(layers "F.Cu" "F.Mask" "F.Paste")
			(net "GND")
		)
		(pad "A87" smd rect
			(at 35.599878 -1.1557 180)
			(size 0.5588 2.3114)
			(layers "F.Cu" "F.Mask" "F.Paste")
			(net "PCIE_TX_N57")
		)
		(pad "A88" smd rect
			(at 36.399978 -1.1557 180)
			(size 0.5588 2.3114)
			(layers "F.Cu" "F.Mask" "F.Paste")
			(net "PCIE_TX_P57")
		)
		(pad "A89" smd rect
			(at 37.200078 -1.1557 180)
			(size 0.5588 2.3114)
			(layers "F.Cu" "F.Mask" "F.Paste")
			(net "GND")
		)
		(pad "A90" smd rect
			(at 37.999924 -1.1557 180)
			(size 0.5588 2.3114)
			(layers "F.Cu" "F.Mask" "F.Paste")
			(net "GND")
		)
		(pad "A91" smd rect
			(at 38.800024 -1.1557 180)
			(size 0.5588 2.3114)
			(layers "F.Cu" "F.Mask" "F.Paste")
			(net "PCIE_TX_N58")
		)
		(pad "A92" smd rect
			(at 39.600124 -1.1557 180)
			(size 0.5588 2.3114)
			(layers "F.Cu" "F.Mask" "F.Paste")
			(net "PCIE_TX_P58")
		)
		(pad "A93" smd rect
			(at 40.39997 -1.1557 180)
			(size 0.5588 2.3114)
			(layers "F.Cu" "F.Mask" "F.Paste")
			(net "GND")
		)
		(pad "A94" smd rect
			(at 41.20007 -1.1557 180)
			(size 0.5588 2.3114)
			(layers "F.Cu" "F.Mask" "F.Paste")
			(net "GND")
		)
		(pad "A95" smd rect
			(at 41.999916 -1.1557 180)
			(size 0.5588 2.3114)
			(layers "F.Cu" "F.Mask" "F.Paste")
			(net "PCIE_TX_N59")
		)
		(pad "A96" smd rect
			(at 42.800016 -1.1557 180)
			(size 0.5588 2.3114)
			(layers "F.Cu" "F.Mask" "F.Paste")
			(net "PCIE_TX_P59")
		)
		(pad "A97" smd rect
			(at 43.600116 -1.1557 180)
			(size 0.5588 2.3114)
			(layers "F.Cu" "F.Mask" "F.Paste")
			(net "GND")
		)
		(pad "A98" smd rect
			(at 44.399962 -1.1557 180)
			(size 0.5588 2.3114)
			(layers "F.Cu" "F.Mask" "F.Paste")
			(net "SSD_PRSNT#6_R")
		)
		(pad "A99" smd rect
			(at 45.200062 -1.1557 180)
			(size 0.5588 2.3114)
			(layers "F.Cu" "F.Mask" "F.Paste")
			(net "SSD_ATNLED#6_R")
		)
		(pad "A100" smd rect
			(at 45.999908 -1.1557 180)
			(size 0.5588 1.8796)
			(drill
				(offset 0 -0.2159)
			)
			(layers "F.Cu" "F.Mask" "F.Paste")
			(net "SSD_PWREN6_R")
		)
		(pad "B1" smd rect
			(at -36.399978 -0.7747 180)
			(size 0.5588 2.3114)
			(drill
				(offset 0 -0.381)
			)
			(layers "F.Cu" "F.Mask" "F.Paste")
			(net "SSD_PERST#11_R")
		)
		(pad "B2" smd rect
			(at -35.599878 -0.7747 180)
			(size 0.5588 2.3114)
			(drill
				(offset 0 -0.381)
			)
			(layers "F.Cu" "F.Mask" "F.Paste")
			(net "SSD_PERST#2_R")
		)
		(pad "B3" smd rect
			(at -34.800032 -0.7747 180)
			(size 0.5588 2.3114)
			(drill
				(offset 0 -0.381)
			)
			(layers "F.Cu" "F.Mask" "F.Paste")
			(net "GND")
		)
		(pad "B4" smd rect
			(at -33.999932 -0.7747 180)
			(size 0.5588 2.3114)
			(drill
				(offset 0 -0.381)
			)
			(layers "F.Cu" "F.Mask" "F.Paste")
			(net "PCIE_RX_N38")
		)
		(pad "B5" smd rect
			(at -33.200086 -0.7747 180)
			(size 0.5588 2.3114)
			(drill
				(offset 0 -0.381)
			)
			(layers "F.Cu" "F.Mask" "F.Paste")
			(net "PCIE_RX_P38")
		)
		(pad "B6" smd rect
			(at -32.399986 -0.7747 180)
			(size 0.5588 2.3114)
			(drill
				(offset 0 -0.381)
			)
			(layers "F.Cu" "F.Mask" "F.Paste")
			(net "GND")
		)
		(pad "B7" smd rect
			(at -31.599886 -0.7747 180)
			(size 0.5588 2.3114)
			(drill
				(offset 0 -0.381)
			)
			(layers "F.Cu" "F.Mask" "F.Paste")
			(net "GND")
		)
		(pad "B8" smd rect
			(at -30.80004 -0.7747 180)
			(size 0.5588 2.3114)
			(drill
				(offset 0 -0.381)
			)
			(layers "F.Cu" "F.Mask" "F.Paste")
			(net "PCIE_RX_N39")
		)
		(pad "B9" smd rect
			(at -29.99994 -0.7747 180)
			(size 0.5588 2.3114)
			(drill
				(offset 0 -0.381)
			)
			(layers "F.Cu" "F.Mask" "F.Paste")
			(net "PCIE_RX_P39")
		)
		(pad "B10" smd rect
			(at -29.200094 -0.7747 180)
			(size 0.5588 2.3114)
			(drill
				(offset 0 -0.381)
			)
			(layers "F.Cu" "F.Mask" "F.Paste")
			(net "GND")
		)
		(pad "B11" smd rect
			(at -28.399994 -0.7747 180)
			(size 0.5588 2.3114)
			(drill
				(offset 0 -0.381)
			)
			(layers "F.Cu" "F.Mask" "F.Paste")
			(net "SSD_PERST#12_R")
		)
		(pad "B12" smd rect
			(at -27.599894 -0.7747 180)
			(size 0.5588 2.3114)
			(drill
				(offset 0 -0.381)
			)
			(layers "F.Cu" "F.Mask" "F.Paste")
			(net "SSD_PWREN12_R")
		)
		(pad "B13" smd rect
			(at -26.800048 -0.7747 180)
			(size 0.5588 2.3114)
			(drill
				(offset 0 -0.381)
			)
			(layers "F.Cu" "F.Mask" "F.Paste")
			(net "SSD_ATNLED#12_R")
		)
	)
)
